(kicad_pcb
	(version 20260206)
	(generator "pcbnew")
	(generator_version "10.0")
	(general
		(thickness 1.6)
		(legacy_teardrops no)
	)
	(paper "A4")
	(title_block
		(title "Wiwynn_Tioga_Pass_MB.brd")
		(comment 1 "Tioga Pass / footprints 3975-3981 of 4770")
	)
	(layers
		(0 "F.Cu" signal "TOP")
		(4 "In1.Cu" signal "L2GND")
		(6 "In2.Cu" signal "L3")
		(8 "In3.Cu" signal "L4GND")
		(10 "In4.Cu" signal "L5")
		(12 "In5.Cu" signal "L6GND")
		(14 "In6.Cu" signal "L7VCC")
		(16 "In7.Cu" signal "L8VCC")
		(18 "In8.Cu" signal "L9GND")
		(20 "In9.Cu" signal "L10")
		(22 "In10.Cu" signal "L11GND")
		(24 "In11.Cu" signal "L12")
		(26 "In12.Cu" signal "L13GND")
		(2 "B.Cu" signal "BOTTOM")
		(9 "F.Adhes" user "F.Adhesive")
		(11 "B.Adhes" user "B.Adhesive")
		(13 "F.Paste" user "Package Geometry/Pastemask Top")
		(15 "B.Paste" user "Package Geometry/Pastemask Bottom")
		(5 "F.SilkS" user "Ref Des/Silkscreen Top")
		(7 "B.SilkS" user "Ref Des/Silkscreen Bottom")
		(1 "F.Mask" user "Board Geometry/Soldermask Top")
		(3 "B.Mask" user "Board Geometry/Soldermask Bottom")
		(17 "Dwgs.User" user "User.Drawings")
		(19 "Cmts.User" user "User.Comments")
		(21 "Eco1.User" user "User.Eco1")
		(23 "Eco2.User" user "User.Eco2")
		(25 "Edge.Cuts" user "Board Geometry/Outline")
		(27 "Margin" user)
		(31 "F.CrtYd" user "Package Geometry/Place Bound Top")
		(29 "B.CrtYd" user "Package Geometry/Place Bound Bottom")
		(35 "F.Fab" user "Ref Des/Assembly Top")
		(33 "B.Fab" user "Ref Des/Assembly Bottom")
	)
	(footprint ""
		(layer "B.Cu")
		(at 370.29009 -66.300604)
		(property "Reference" "R3R11"
			(at 0 0 0)
			(layer "B.SilkS")
			(hide yes)
			(effects
				(font
					(size 1.27 1.27)
				)
				(justify mirror)
			)
		)
		(property "Value" ""
			(at 0 0 0)
			(layer "B.Fab")
			(effects
				(font
					(size 1.27 1.27)
				)
				(justify mirror)
			)
		)
		(duplicate_pad_numbers_are_jumpers no)
		(fp_poly
			(pts
				(xy 0.2794 -0.1016) (xy -0.2794 -0.1016) (xy -0.2794 0.9906) (xy 0.2794 0.9906)
			)
			(stroke
				(width 0)
				(type default)
			)
			(fill no)
			(layer "B.CrtYd")
		)
		(fp_line
			(start -0.2794 -0.1016)
			(end 0.2794 -0.1016)
			(stroke
				(width 0.1)
				(type default)
			)
			(layer "B.Fab")
		)
		(fp_line
			(start -0.2794 0.9906)
			(end -0.2794 -0.1016)
			(stroke
				(width 0.1)
				(type default)
			)
			(layer "B.Fab")
		)
		(fp_line
			(start 0.2794 -0.1016)
			(end 0.2794 0.9906)
			(stroke
				(width 0.1)
				(type default)
			)
			(layer "B.Fab")
		)
		(fp_line
			(start 0.2794 0.9906)
			(end -0.2794 0.9906)
			(stroke
				(width 0.1)
				(type default)
			)
			(layer "B.Fab")
		)
		(pad "1" smd rect
			(at 0 0 180)
			(size 0.508 0.508)
			(layers "B.Cu" "B.Mask" "B.Paste")
			(net "FM_JTAG_PLD_EN_DEBUG")
		)
		(pad "2" smd rect
			(at 0 0.889 180)
			(size 0.508 0.508)
			(layers "B.Cu" "B.Mask" "B.Paste")
			(net "GND")
		)
		(zone
			(layer "B.Cu")
			(hatch none 0.5)
			(connect_pads
				(clearance 0)
			)
			(min_thickness 0.25)
			(keepout
				(tracks allowed)
				(vias not_allowed)
				(pads allowed)
				(copperpour not_allowed)
				(footprints allowed)
			)
			(placement
				(enabled no)
				(sheetname "")
			)
			(fill
				(thermal_gap 0.5)
				(thermal_bridge_width 0.5)
				(island_removal_mode 0)
			)
			(polygon
				(pts
					(xy 370.54409 -66.046604) (xy 370.03609 -66.046604) (xy 370.03609 -65.665604) (xy 370.54409 -65.665604)
				)
			)
		)
		(zone
			(layer "B.Cu")
			(hatch none 0.5)
			(connect_pads
				(clearance 0)
			)
			(min_thickness 0.25)
			(keepout
				(tracks not_allowed)
				(vias allowed)
				(pads allowed)
				(copperpour not_allowed)
				(footprints allowed)
			)
			(placement
				(enabled no)
				(sheetname "")
			)
			(fill
				(thermal_gap 0.5)
				(thermal_bridge_width 0.5)
				(island_removal_mode 0)
			)
			(polygon
				(pts
					(xy 370.54409 -65.665604) (xy 370.03609 -65.665604) (xy 370.03609 -66.046604) (xy 370.54409 -66.046604)
				)
			)
		)
	)
	(footprint ""
		(layer "B.Cu")
		(at 373.761 -6.1595)
		(property "Reference" "R7G31"
			(at 0 0 0)
			(layer "B.SilkS")
			(hide yes)
			(effects
				(font
					(size 1.27 1.27)
				)
				(justify mirror)
			)
		)
		(property "Value" ""
			(at 0 0 0)
			(layer "B.Fab")
			(effects
				(font
					(size 1.27 1.27)
				)
				(justify mirror)
			)
		)
		(duplicate_pad_numbers_are_jumpers no)
		(fp_poly
			(pts
				(xy 0.2794 -0.1016) (xy -0.2794 -0.1016) (xy -0.2794 0.9906) (xy 0.2794 0.9906)
			)
			(stroke
				(width 0)
				(type default)
			)
			(fill no)
			(layer "B.CrtYd")
		)
		(fp_line
			(start -0.2794 -0.1016)
			(end 0.2794 -0.1016)
			(stroke
				(width 0.1)
				(type default)
			)
			(layer "B.Fab")
		)
		(fp_line
			(start -0.2794 0.9906)
			(end -0.2794 -0.1016)
			(stroke
				(width 0.1)
				(type default)
			)
			(layer "B.Fab")
		)
		(fp_line
			(start 0.2794 -0.1016)
			(end 0.2794 0.9906)
			(stroke
				(width 0.1)
				(type default)
			)
			(layer "B.Fab")
		)
		(fp_line
			(start 0.2794 0.9906)
			(end -0.2794 0.9906)
			(stroke
				(width 0.1)
				(type default)
			)
			(layer "B.Fab")
		)
		(pad "1" smd rect
			(at 0 0 180)
			(size 0.508 0.508)
			(layers "B.Cu" "B.Mask" "B.Paste")
			(net "P3V3_STBY")
		)
		(pad "2" smd rect
			(at 0 0.889 180)
			(size 0.508 0.508)
			(layers "B.Cu" "B.Mask" "B.Paste")
			(net "PU_BIOS_RECOVER_BOOT")
		)
		(zone
			(layer "B.Cu")
			(hatch none 0.5)
			(connect_pads
				(clearance 0)
			)
			(min_thickness 0.25)
			(keepout
				(tracks allowed)
				(vias not_allowed)
				(pads allowed)
				(copperpour not_allowed)
				(footprints allowed)
			)
			(placement
				(enabled no)
				(sheetname "")
			)
			(fill
				(thermal_gap 0.5)
				(thermal_bridge_width 0.5)
				(island_removal_mode 0)
			)
			(polygon
				(pts
					(xy 374.015 -5.9055) (xy 373.507 -5.9055) (xy 373.507 -5.5245) (xy 374.015 -5.5245)
				)
			)
		)
		(zone
			(layer "B.Cu")
			(hatch none 0.5)
			(connect_pads
				(clearance 0)
			)
			(min_thickness 0.25)
			(keepout
				(tracks not_allowed)
				(vias allowed)
				(pads allowed)
				(copperpour not_allowed)
				(footprints allowed)
			)
			(placement
				(enabled no)
				(sheetname "")
			)
			(fill
				(thermal_gap 0.5)
				(thermal_bridge_width 0.5)
				(island_removal_mode 0)
			)
			(polygon
				(pts
					(xy 374.015 -5.5245) (xy 373.507 -5.5245) (xy 373.507 -5.9055) (xy 374.015 -5.9055)
				)
			)
		)
	)
	(footprint ""
		(layer "B.Cu")
		(at 210.847432 -57.023 -90)
		(property "Reference" "C6R9"
			(at -0.86233 -3.401568 0)
			(unlocked yes)
			(layer "B.SilkS")
			(effects
				(font
					(size 0.7874 0.5842)
					(thickness 0.1524)
				)
				(justify mirror)
			)
		)
		(property "Value" ""
			(at 0 0 90)
			(layer "B.Fab")
			(effects
				(font
					(size 1.27 1.27)
				)
				(justify mirror)
			)
		)
		(duplicate_pad_numbers_are_jumpers no)
		(fp_line
			(start -2.286 7.366)
			(end -1.600708 7.366)
			(stroke
				(width 0.1524)
				(type default)
			)
			(layer "B.SilkS")
		)
		(fp_line
			(start -2.286 7.366)
			(end -2.286 1.63195)
			(stroke
				(width 0.1524)
				(type default)
			)
			(layer "B.SilkS")
		)
		(fp_line
			(start 2.286 7.366)
			(end 1.60147 7.366)
			(stroke
				(width 0.1524)
				(type default)
			)
			(layer "B.SilkS")
		)
		(fp_line
			(start 2.286 7.366)
			(end 2.286 1.632712)
			(stroke
				(width 0.1524)
				(type default)
			)
			(layer "B.SilkS")
		)
		(fp_line
			(start -2.504948 1.633728)
			(end -1.6002 1.633728)
			(stroke
				(width 0.1524)
				(type default)
			)
			(layer "B.SilkS")
		)
		(fp_line
			(start 2.563114 1.633728)
			(end 1.6002 1.633728)
			(stroke
				(width 0.1524)
				(type default)
			)
			(layer "B.SilkS")
		)
		(fp_line
			(start -2.504948 -1.616456)
			(end -2.504948 1.633728)
			(stroke
				(width 0.1524)
				(type default)
			)
			(layer "B.SilkS")
		)
		(fp_line
			(start -1.6002 -1.616456)
			(end -2.504948 -1.616456)
			(stroke
				(width 0.1524)
				(type default)
			)
			(layer "B.SilkS")
		)
		(fp_line
			(start 1.6002 -1.616456)
			(end 2.563114 -1.616456)
			(stroke
				(width 0.1524)
				(type default)
			)
			(layer "B.SilkS")
		)
		(fp_line
			(start 2.563114 -1.616456)
			(end 2.563114 1.633728)
			(stroke
				(width 0.1524)
				(type default)
			)
			(layer "B.SilkS")
		)
		(fp_rect
			(start 2.286 7.366)
			(end -2.286 -0.254)
			(stroke
				(width 0)
				(type default)
			)
			(fill no)
			(layer "B.CrtYd")
		)
		(fp_line
			(start -2.286 7.366)
			(end 2.286 7.366)
			(stroke
				(width 0.1)
				(type default)
			)
			(layer "B.Fab")
		)
		(fp_line
			(start 2.286 7.366)
			(end 2.286 -0.254)
			(stroke
				(width 0.1)
				(type default)
			)
			(layer "B.Fab")
		)
		(fp_line
			(start -2.286 -0.254)
			(end -2.286 7.366)
			(stroke
				(width 0.1)
				(type default)
			)
			(layer "B.Fab")
		)
		(fp_line
			(start 2.286 -0.254)
			(end -2.286 -0.254)
			(stroke
				(width 0.1)
				(type default)
			)
			(layer "B.Fab")
		)
		(pad "1" smd rect
			(at 0 0 90)
			(size 2.54 3.048)
			(layers "B.Cu" "B.Mask" "B.Paste")
			(net "PVCCIN_CPU0")
		)
		(pad "2" smd rect
			(at 0 7.112 90)
			(size 2.54 3.048)
			(layers "B.Cu" "B.Mask" "B.Paste")
			(net "GND")
		)
	)
	(footprint ""
		(layer "B.Cu")
		(at 10.414 -68.0466 180)
		(property "Reference" "R9P26"
			(at 0 0 0)
			(layer "B.SilkS")
			(hide yes)
			(effects
				(font
					(size 1.27 1.27)
				)
				(justify mirror)
			)
		)
		(property "Value" ""
			(at 0 0 0)
			(layer "B.Fab")
			(effects
				(font
					(size 1.27 1.27)
				)
				(justify mirror)
			)
		)
		(duplicate_pad_numbers_are_jumpers no)
		(fp_rect
			(start -0.2794 0.9906)
			(end 0.2794 -0.1016)
			(stroke
				(width 0)
				(type default)
			)
			(fill no)
			(layer "B.CrtYd")
		)
		(fp_line
			(start 0.2794 0.9906)
			(end -0.2794 0.9906)
			(stroke
				(width 0.1)
				(type default)
			)
			(layer "B.Fab")
		)
		(fp_line
			(start 0.2794 -0.1016)
			(end 0.2794 0.9906)
			(stroke
				(width 0.1)
				(type default)
			)
			(layer "B.Fab")
		)
		(fp_line
			(start -0.2794 0.9906)
			(end -0.2794 -0.1016)
			(stroke
				(width 0.1)
				(type default)
			)
			(layer "B.Fab")
		)
		(fp_line
			(start -0.2794 -0.1016)
			(end 0.2794 -0.1016)
			(stroke
				(width 0.1)
				(type default)
			)
			(layer "B.Fab")
		)
		(pad "1" smd rect
			(at 0 0)
			(size 0.508 0.508)
			(layers "B.Cu" "B.Mask" "B.Paste")
			(net "P12V_HSC_SENN1")
		)
		(pad "2" smd rect
			(at 0 0.889)
			(size 0.508 0.508)
			(layers "B.Cu" "B.Mask" "B.Paste")
			(net "A_HSC_HSN")
		)
		(zone
			(layer "B.Cu")
			(hatch none 0.5)
			(connect_pads
				(clearance 0)
			)
			(min_thickness 0.25)
			(keepout
				(tracks allowed)
				(vias not_allowed)
				(pads allowed)
				(copperpour not_allowed)
				(footprints allowed)
			)
			(placement
				(enabled no)
				(sheetname "")
			)
			(fill
				(thermal_gap 0.5)
				(thermal_bridge_width 0.5)
				(island_removal_mode 0)
			)
			(polygon
				(pts
					(xy 10.668 -68.6816) (xy 10.16 -68.6816) (xy 10.16 -68.3006) (xy 10.668 -68.3006)
				)
			)
		)
		(zone
			(layer "B.Cu")
			(hatch none 0.5)
			(connect_pads
				(clearance 0)
			)
			(min_thickness 0.25)
			(keepout
				(tracks not_allowed)
				(vias allowed)
				(pads allowed)
				(copperpour not_allowed)
				(footprints allowed)
			)
			(placement
				(enabled no)
				(sheetname "")
			)
			(fill
				(thermal_gap 0.5)
				(thermal_bridge_width 0.5)
				(island_removal_mode 0)
			)
			(polygon
				(pts
					(xy 10.668 -68.6816) (xy 10.16 -68.6816) (xy 10.16 -68.3006) (xy 10.668 -68.3006)
				)
			)
		)
	)
	(footprint ""
		(layer "B.Cu")
		(at 487.934 -111.94542 90)
		(property "Reference" "C1M26"
			(at 0 0 90)
			(layer "B.SilkS")
			(hide yes)
			(effects
				(font
					(size 1.27 1.27)
				)
				(justify mirror)
			)
		)
		(property "Value" ""
			(at 0 0 90)
			(layer "B.Fab")
			(effects
				(font
					(size 1.27 1.27)
				)
				(justify mirror)
			)
		)
		(duplicate_pad_numbers_are_jumpers no)
		(fp_rect
			(start -0.7239 -0.2159)
			(end 0.7239 1.9939)
			(stroke
				(width 0)
				(type default)
			)
			(fill no)
			(layer "B.CrtYd")
		)
		(fp_line
			(start 0.7239 -0.2159)
			(end 0.7239 1.9939)
			(stroke
				(width 0.1)
				(type default)
			)
			(layer "B.Fab")
		)
		(fp_line
			(start -0.7239 -0.2159)
			(end 0.7239 -0.2159)
			(stroke
				(width 0.1)
				(type default)
			)
			(layer "B.Fab")
		)
		(fp_line
			(start 0.7239 1.9939)
			(end -0.7239 1.9939)
			(stroke
				(width 0.1)
				(type default)
			)
			(layer "B.Fab")
		)
		(fp_line
			(start -0.7239 1.9939)
			(end -0.7239 -0.2159)
			(stroke
				(width 0.1)
				(type default)
			)
			(layer "B.Fab")
		)
		(pad "1" smd rect
			(at 0 0 270)
			(size 1.27 1.016)
			(layers "B.Cu" "B.Mask" "B.Paste")
			(net "P12V_STBY")
		)
		(pad "2" smd rect
			(at 0 1.778 270)
			(size 1.27 1.016)
			(layers "B.Cu" "B.Mask" "B.Paste")
			(net "GND")
		)
		(zone
			(layer "B.Cu")
			(hatch none 0.5)
			(connect_pads
				(clearance 0)
			)
			(min_thickness 0.25)
			(keepout
				(tracks not_allowed)
				(vias allowed)
				(pads allowed)
				(copperpour not_allowed)
				(footprints allowed)
			)
			(placement
				(enabled no)
				(sheetname "")
			)
			(fill
				(thermal_gap 0.5)
				(thermal_bridge_width 0.5)
				(island_removal_mode 0)
			)
			(polygon
				(pts
					(xy 488.442 -111.31042) (xy 489.204 -111.31042) (xy 489.204 -112.58042) (xy 488.442 -112.58042)
				)
			)
		)
	)
	(footprint ""
		(layer "B.Cu")
		(at 460.6544 -52.457858)
		(property "Reference" "C1R3"
			(at 0 0 0)
			(layer "B.SilkS")
			(hide yes)
			(effects
				(font
					(size 1.27 1.27)
				)
				(justify mirror)
			)
		)
		(property "Value" ""
			(at 0 0 0)
			(layer "B.Fab")
			(effects
				(font
					(size 1.27 1.27)
				)
				(justify mirror)
			)
		)
		(duplicate_pad_numbers_are_jumpers no)
		(fp_poly
			(pts
				(xy -0.3048 -0.1016) (xy -0.3048 0.9906) (xy 0.3048 0.9906) (xy 0.3048 -0.1016)
			)
			(stroke
				(width 0)
				(type default)
			)
			(fill no)
			(layer "B.CrtYd")
		)
		(fp_line
			(start -0.3048 -0.1016)
			(end 0.3048 -0.1016)
			(stroke
				(width 0.1)
				(type default)
			)
			(layer "B.Fab")
		)
		(fp_line
			(start -0.3048 0.9906)
			(end -0.3048 -0.1016)
			(stroke
				(width 0.1)
				(type default)
			)
			(layer "B.Fab")
		)
		(fp_line
			(start 0.3048 -0.1016)
			(end 0.3048 0.9906)
			(stroke
				(width 0.1)
				(type default)
			)
			(layer "B.Fab")
		)
		(fp_line
			(start 0.3048 0.9906)
			(end -0.3048 0.9906)
			(stroke
				(width 0.1)
				(type default)
			)
			(layer "B.Fab")
		)
		(pad "1" smd rect
			(at 0 0 180)
			(size 0.508 0.508)
			(layers "B.Cu" "B.Mask" "B.Paste")
			(net "P3E_CPU0_PE3_OCP_TXN<1>")
		)
		(pad "2" smd rect
			(at 0 0.889 180)
			(size 0.508 0.508)
			(layers "B.Cu" "B.Mask" "B.Paste")
			(net "P3E_OCP_CPU0_PE3_C_TXN<1>")
		)
		(zone
			(layer "B.Cu")
			(hatch none 0.5)
			(connect_pads
				(clearance 0)
			)
			(min_thickness 0.25)
			(keepout
				(tracks allowed)
				(vias not_allowed)
				(pads allowed)
				(copperpour not_allowed)
				(footprints allowed)
			)
			(placement
				(enabled no)
				(sheetname "")
			)
			(fill
				(thermal_gap 0.5)
				(thermal_bridge_width 0.5)
				(island_removal_mode 0)
			)
			(polygon
				(pts
					(xy 460.9084 -52.203858) (xy 460.4004 -52.203858) (xy 460.4004 -51.822858) (xy 460.9084 -51.822858)
				)
			)
		)
		(zone
			(layer "B.Cu")
			(hatch none 0.5)
			(connect_pads
				(clearance 0)
			)
			(min_thickness 0.25)
			(keepout
				(tracks not_allowed)
				(vias allowed)
				(pads allowed)
				(copperpour not_allowed)
				(footprints allowed)
			)
			(placement
				(enabled no)
				(sheetname "")
			)
			(fill
				(thermal_gap 0.5)
				(thermal_bridge_width 0.5)
				(island_removal_mode 0)
			)
			(polygon
				(pts
					(xy 460.9084 -51.822858) (xy 460.4004 -51.822858) (xy 460.4004 -52.203858) (xy 460.9084 -52.203858)
				)
			)
		)
	)
	(footprint ""
		(layer "B.Cu")
		(at 415.29 -31.0515 180)
		(property "Reference" "C25W38"
			(at 0.8382 -0.67818 180)
			(unlocked yes)
			(layer "B.SilkS")
			(effects
				(font
					(size 0.4064 0.254)
					(thickness 0.1524)
				)
				(justify left mirror)
			)
		)
		(property "Value" ""
			(at 0 0 0)
			(layer "B.Fab")
			(effects
				(font
					(size 1.27 1.27)
				)
				(justify mirror)
			)
		)
		(duplicate_pad_numbers_are_jumpers no)
		(fp_poly
			(pts
				(xy -0.3048 -0.1016) (xy -0.3048 0.9906) (xy 0.3048 0.9906) (xy 0.3048 -0.1016)
			)
			(stroke
				(width 0)
				(type default)
			)
			(fill no)
			(layer "B.CrtYd")
		)
		(fp_line
			(start 0.3048 0.9906)
			(end -0.3048 0.9906)
			(stroke
				(width 0.1)
				(type default)
			)
			(layer "B.Fab")
		)
		(fp_line
			(start 0.3048 -0.1016)
			(end 0.3048 0.9906)
			(stroke
				(width 0.1)
				(type default)
			)
			(layer "B.Fab")
		)
		(fp_line
			(start -0.3048 0.9906)
			(end -0.3048 -0.1016)
			(stroke
				(width 0.1)
				(type default)
			)
			(layer "B.Fab")
		)
		(fp_line
			(start -0.3048 -0.1016)
			(end 0.3048 -0.1016)
			(stroke
				(width 0.1)
				(type default)
			)
			(layer "B.Fab")
		)
		(pad "1" smd rect
			(at 0 0)
			(size 0.508 0.508)
			(layers "B.Cu" "B.Mask" "B.Paste")
			(net "VCC_A_1V1")
		)
		(pad "2" smd rect
			(at 0 0.889)
			(size 0.508 0.508)
			(layers "B.Cu" "B.Mask" "B.Paste")
			(net "GND")
		)
		(zone
			(layer "B.Cu")
			(hatch none 0.5)
			(connect_pads
				(clearance 0)
			)
			(min_thickness 0.25)
			(keepout
				(tracks not_allowed)
				(vias allowed)
				(pads allowed)
				(copperpour not_allowed)
				(footprints allowed)
			)
			(placement
				(enabled no)
				(sheetname "")
			)
			(fill
				(thermal_gap 0.5)
				(thermal_bridge_width 0.5)
				(island_removal_mode 0)
			)
			(polygon
				(pts
					(xy 415.036 -31.6865) (xy 415.544 -31.6865) (xy 415.544 -31.3055) (xy 415.036 -31.3055)
				)
			)
		)
		(zone
			(layer "B.Cu")
			(hatch none 0.5)
			(connect_pads
				(clearance 0)
			)
			(min_thickness 0.25)
			(keepout
				(tracks allowed)
				(vias not_allowed)
				(pads allowed)
				(copperpour not_allowed)
				(footprints allowed)
			)
			(placement
				(enabled no)
				(sheetname "")
			)
			(fill
				(thermal_gap 0.5)
				(thermal_bridge_width 0.5)
				(island_removal_mode 0)
			)
			(polygon
				(pts
					(xy 415.036 -31.3055) (xy 415.544 -31.3055) (xy 415.544 -31.6865) (xy 415.036 -31.6865)
				)
			)
		)
	)
)
